# S9S_MB_2U (Grand Teton) — schematic netlist excerpt (pin names and nets, part order shuffled) for the footprints in the layout excerpt that follows; sources: Cadence DE-HDL packaged netlist, KiCad conversion of 03242023_DA0F0TMBIJ0_F0T_Motherboard_J_brd_V01_OCP.brd

H104  HOLE  EMPTY  pkg TH  page 311 : \1\ = GND
R3441  Q_RES  0 5% CHIP  pkg 0402LF  page 144 : A = GPU_BASE_ID1 ; B = GND
R3492  Q_RES  54.9K 1% CHIP  pkg 0402LF  page 150 : A = P3V3_AUX ; B = GPU_FPGA_EROT_RST_BUF_R_N

(kicad_pcb
	(version 20260206)
	(generator "pcbnew")
	(generator_version "10.0")
	(general
		(thickness 1.6)
		(legacy_teardrops no)
	)
	(paper "A4")
	(title_block
		(title "03242023_DA0F0TMBIJ0_F0T_Motherboard_J_brd_V01_OCP.brd")
		(comment 1 "Grand Teton / footprints 131-133 of 6105")
	)
	(layers
		(0 "F.Cu" signal "TOP")
		(4 "In1.Cu" signal "GND")
		(6 "In2.Cu" signal "IN1")
		(8 "In3.Cu" signal "GND1")
		(10 "In4.Cu" signal "IN2")
		(12 "In5.Cu" signal "GND2")
		(14 "In6.Cu" signal "IN3")
		(16 "In7.Cu" signal "GND3")
		(18 "In8.Cu" signal "VCC")
		(20 "In9.Cu" signal "VCC1")
		(22 "In10.Cu" signal "GND4")
		(24 "In11.Cu" signal "IN4")
		(26 "In12.Cu" signal "GND5")
		(28 "In13.Cu" signal "IN5")
		(30 "In14.Cu" signal "GND6")
		(32 "In15.Cu" signal "IN6")
		(34 "In16.Cu" signal "GND7")
		(2 "B.Cu" signal "BOTTOM")
		(9 "F.Adhes" user "F.Adhesive")
		(11 "B.Adhes" user "B.Adhesive")
		(13 "F.Paste" user "Package Geometry/Pastemask Top")
		(15 "B.Paste" user "Package Geometry/Pastemask Bottom")
		(5 "F.SilkS" user "Ref Des/Silkscreen Top")
		(7 "B.SilkS" user "Ref Des/Silkscreen Bottom")
		(1 "F.Mask" user "Board Geometry/Soldermask Top")
		(3 "B.Mask" user "Board Geometry/Soldermask Bottom")
		(17 "Dwgs.User" user "User.Drawings")
		(19 "Cmts.User" user "User.Comments")
		(21 "Eco1.User" user "User.Eco1")
		(23 "Eco2.User" user "User.Eco2")
		(25 "Edge.Cuts" user "Board Geometry/Outline")
		(27 "Margin" user)
		(31 "F.CrtYd" user "Package Geometry/Place Bound Top")
		(29 "B.CrtYd" user "Package Geometry/Place Bound Bottom")
		(35 "F.Fab" user "Ref Des/Assembly Top")
		(33 "B.Fab" user "Ref Des/Assembly Bottom")
	)
	(footprint ""
		(layer "F.Cu")
		(at 101.833934 -395.42974)
		(property "Reference" "R3492"
			(at 0 0 0)
			(layer "F.SilkS")
			(hide yes)
			(effects
				(font
					(size 1.27 1.27)
				)
			)
		)
		(property "Value" ""
			(at 0 0 0)
			(layer "F.Fab")
			(effects
				(font
					(size 1.27 1.27)
				)
			)
		)
		(duplicate_pad_numbers_are_jumpers no)
		(fp_line
			(start -0.7874 -0.4064)
			(end 0.7874 -0.4064)
			(stroke
				(width 0.1524)
				(type default)
			)
			(layer "F.SilkS")
		)
		(fp_line
			(start -0.7874 0.4064)
			(end -0.7874 -0.4064)
			(stroke
				(width 0.1524)
				(type default)
			)
			(layer "F.SilkS")
		)
		(fp_line
			(start 0.7874 -0.4064)
			(end 0.7874 0.4064)
			(stroke
				(width 0.1524)
				(type default)
			)
			(layer "F.SilkS")
		)
		(fp_line
			(start 0.7874 0.4064)
			(end -0.7874 0.4064)
			(stroke
				(width 0.1524)
				(type default)
			)
			(layer "F.SilkS")
		)
		(fp_line
			(start -0.67945 -0.305054)
			(end -0.12065 -0.305054)
			(stroke
				(width 0.1)
				(type default)
			)
			(layer "F.Fab")
		)
		(fp_line
			(start -0.67945 0.3048)
			(end -0.67945 -0.305054)
			(stroke
				(width 0.1)
				(type default)
			)
			(layer "F.Fab")
		)
		(fp_line
			(start -0.12065 -0.305054)
			(end -0.12065 -0.2794)
			(stroke
				(width 0.1)
				(type default)
			)
			(layer "F.Fab")
		)
		(fp_line
			(start -0.12065 -0.2794)
			(end 0.12065 -0.2794)
			(stroke
				(width 0.1)
				(type default)
			)
			(layer "F.Fab")
		)
		(fp_line
			(start -0.12065 0.2794)
			(end -0.12065 0.3048)
			(stroke
				(width 0.1)
				(type default)
			)
			(layer "F.Fab")
		)
		(fp_line
			(start -0.12065 0.3048)
			(end -0.67945 0.3048)
			(stroke
				(width 0.1)
				(type default)
			)
			(layer "F.Fab")
		)
		(fp_line
			(start 0.120396 0.2794)
			(end -0.12065 0.2794)
			(stroke
				(width 0.1)
				(type default)
			)
			(layer "F.Fab")
		)
		(fp_line
			(start 0.120396 0.3048)
			(end 0.120396 0.2794)
			(stroke
				(width 0.1)
				(type default)
			)
			(layer "F.Fab")
		)
		(fp_line
			(start 0.12065 -0.3048)
			(end 0.67945 -0.3048)
			(stroke
				(width 0.1)
				(type default)
			)
			(layer "F.Fab")
		)
		(fp_line
			(start 0.12065 -0.2794)
			(end 0.12065 -0.3048)
			(stroke
				(width 0.1)
				(type default)
			)
			(layer "F.Fab")
		)
		(fp_line
			(start 0.67945 -0.3048)
			(end 0.67945 0.3048)
			(stroke
				(width 0.1)
				(type default)
			)
			(layer "F.Fab")
		)
		(fp_line
			(start 0.67945 0.3048)
			(end 0.120396 0.3048)
			(stroke
				(width 0.1)
				(type default)
			)
			(layer "F.Fab")
		)
		(pad "1" smd circle
			(at -0.40005 0)
			(size 0 0)
			(layers "F.Cu" "F.Mask" "F.Paste")
			(net "P3V3_AUX")
		)
		(pad "2" smd circle
			(at 0.40005 0)
			(size 0 0)
			(layers "F.Cu" "F.Mask" "F.Paste")
			(net "GPU_FPGA_EROT_RST_BUF_R_N")
		)
	)
	(footprint ""
		(layer "F.Cu")
		(at 19.769582 -428.024036 90)
		(property "Reference" "R3441"
			(at 0 0 90)
			(layer "F.SilkS")
			(hide yes)
			(effects
				(font
					(size 1.27 1.27)
				)
			)
		)
		(property "Value" ""
			(at 0 0 90)
			(layer "F.Fab")
			(effects
				(font
					(size 1.27 1.27)
				)
			)
		)
		(duplicate_pad_numbers_are_jumpers no)
		(fp_line
			(start 0.7874 -0.4064)
			(end 0.7874 0.4064)
			(stroke
				(width 0.1524)
				(type default)
			)
			(layer "F.SilkS")
		)
		(fp_line
			(start -0.7874 -0.4064)
			(end 0.7874 -0.4064)
			(stroke
				(width 0.1524)
				(type default)
			)
			(layer "F.SilkS")
		)
		(fp_line
			(start 0.7874 0.4064)
			(end -0.7874 0.4064)
			(stroke
				(width 0.1524)
				(type default)
			)
			(layer "F.SilkS")
		)
		(fp_line
			(start -0.7874 0.4064)
			(end -0.7874 -0.4064)
			(stroke
				(width 0.1524)
				(type default)
			)
			(layer "F.SilkS")
		)
		(fp_line
			(start -0.12065 -0.305054)
			(end -0.12065 -0.2794)
			(stroke
				(width 0.1)
				(type default)
			)
			(layer "F.Fab")
		)
		(fp_line
			(start -0.67945 -0.305054)
			(end -0.12065 -0.305054)
			(stroke
				(width 0.1)
				(type default)
			)
			(layer "F.Fab")
		)
		(fp_line
			(start 0.67945 -0.3048)
			(end 0.67945 0.3048)
			(stroke
				(width 0.1)
				(type default)
			)
			(layer "F.Fab")
		)
		(fp_line
			(start 0.12065 -0.3048)
			(end 0.67945 -0.3048)
			(stroke
				(width 0.1)
				(type default)
			)
			(layer "F.Fab")
		)
		(fp_line
			(start 0.12065 -0.2794)
			(end 0.12065 -0.3048)
			(stroke
				(width 0.1)
				(type default)
			)
			(layer "F.Fab")
		)
		(fp_line
			(start -0.12065 -0.2794)
			(end 0.12065 -0.2794)
			(stroke
				(width 0.1)
				(type default)
			)
			(layer "F.Fab")
		)
		(fp_line
			(start 0.120396 0.2794)
			(end -0.12065 0.2794)
			(stroke
				(width 0.1)
				(type default)
			)
			(layer "F.Fab")
		)
		(fp_line
			(start -0.12065 0.2794)
			(end -0.12065 0.3048)
			(stroke
				(width 0.1)
				(type default)
			)
			(layer "F.Fab")
		)
		(fp_line
			(start 0.67945 0.3048)
			(end 0.120396 0.3048)
			(stroke
				(width 0.1)
				(type default)
			)
			(layer "F.Fab")
		)
		(fp_line
			(start 0.120396 0.3048)
			(end 0.120396 0.2794)
			(stroke
				(width 0.1)
				(type default)
			)
			(layer "F.Fab")
		)
		(fp_line
			(start -0.12065 0.3048)
			(end -0.67945 0.3048)
			(stroke
				(width 0.1)
				(type default)
			)
			(layer "F.Fab")
		)
		(fp_line
			(start -0.67945 0.3048)
			(end -0.67945 -0.305054)
			(stroke
				(width 0.1)
				(type default)
			)
			(layer "F.Fab")
		)
		(pad "1" smd circle
			(at -0.40005 0 90)
			(size 0 0)
			(layers "F.Cu" "F.Mask" "F.Paste")
			(net "GPU_BASE_ID1")
		)
		(pad "2" smd circle
			(at 0.40005 0 90)
			(size 0 0)
			(layers "F.Cu" "F.Mask" "F.Paste")
			(net "GND")
		)
	)
	(footprint ""
		(layer "F.Cu")
		(at 461.459834 -160.50006)
		(property "Reference" "H104"
			(at -6.563614 -4.53263 0)
			(unlocked yes)
			(layer "F.SilkS")
			(effects
				(font
					(size 0.7874 0.5842)
					(thickness 0.1524)
				)
				(justify left)
			)
		)
		(property "Value" ""
			(at 0 0 0)
			(layer "F.Fab")
			(effects
				(font
					(size 1.27 1.27)
				)
			)
		)
		(duplicate_pad_numbers_are_jumpers no)
		(pad "1" thru_hole circle
			(at 0 0)
			(size 10.0076 10.0076)
			(drill 5.6134)
			(layers "*.Cu" "*.Mask")
			(remove_unused_layers no)
			(net "GND")
			(clearance -1.9431)
		)
	)
)
